(kicad_pcb
	(version 20241229)
	(generator "pcbnew")
	(generator_version "9.0")
	(general
		(thickness 1.6642)
		(legacy_teardrops no)
	)
	(paper "A3")
	(title_block
		(title "PolarFire SoM")
		(date "2025-07-22")
		(rev "1.1.4")
		(company "Antmicro Ltd")
		(comment 1 "www.antmicro.com")
		(comment 9 "footprints 314-317 of 470")
	)
	(layers
		(0 "F.Cu" mixed)
		(4 "In1.Cu" power)
		(6 "In2.Cu" signal)
		(8 "In3.Cu" power)
		(10 "In4.Cu" signal)
		(12 "In5.Cu" power)
		(14 "In6.Cu" power)
		(16 "In7.Cu" signal)
		(18 "In8.Cu" power)
		(20 "In9.Cu" signal)
		(22 "In10.Cu" power)
		(24 "In11.Cu" signal)
		(26 "In12.Cu" signal)
		(2 "B.Cu" mixed)
		(9 "F.Adhes" user "F.Adhesive")
		(11 "B.Adhes" user "B.Adhesive")
		(13 "F.Paste" user)
		(15 "B.Paste" user)
		(5 "F.SilkS" user "F.Silkscreen")
		(7 "B.SilkS" user "B.Silkscreen")
		(1 "F.Mask" user)
		(3 "B.Mask" user)
		(17 "Dwgs.User" user "User.Drawings")
		(19 "Cmts.User" user "User.Comments")
		(21 "Eco1.User" user "User.Eco1")
		(23 "Eco2.User" user "User.Eco2")
		(25 "Edge.Cuts" user)
		(27 "Margin" user)
		(31 "F.CrtYd" user "F.Courtyard")
		(29 "B.CrtYd" user "B.Courtyard")
		(35 "F.Fab" user)
		(33 "B.Fab" user)
	)
	(footprint "antmicro-footprints:C_0402_1005Metric"
		(layer "B.Cu")
		(at 175.25 134.66 90)
		(descr "Capacitor SMD 0402")
		(tags "capacitor SMD 0402")
		(property "Reference" "C122"
			(at 2.12 1.38 90)
			(layer "B.SilkS")
			(effects
				(font
					(size 0.7 0.7)
					(thickness 0.15)
				)
				(justify left bottom mirror)
			)
		)
		(property "Value" "C_1u_0402"
			(at -1.022927 -2.155213 270)
			(layer "B.Fab")
			(hide yes)
			(effects
				(font
					(size 0.7 0.7)
					(thickness 0.15)
				)
				(justify left bottom mirror)
			)
		)
		(property "Datasheet" "https://product.tdk.com/en/search/capacitor/ceramic/mlcc/info?part_no=C1005X6S1A105K050BC"
			(at 0 0 90)
			(layer "F.Fab")
			(hide yes)
			(effects
				(font
					(size 1.27 1.27)
					(thickness 0.15)
				)
			)
		)
		(property "Description" "SMD Multilayer Ceramic Capacitor, 1 µF, 10 V, 0402 [1005 Metric], ± 10%, X6S, C"
			(at 0 0 90)
			(layer "F.Fab")
			(hide yes)
			(effects
				(font
					(size 1.27 1.27)
					(thickness 0.15)
				)
			)
		)
		(property "Author" "Antmicro"
			(at 309.91 -40.59 0)
			(layer "B.Fab")
			(hide yes)
			(effects
				(font
					(size 1 1)
					(thickness 0.15)
				)
				(justify mirror)
			)
		)
		(property "Dielectric" "X5R"
			(at 309.91 -40.59 0)
			(layer "B.Fab")
			(hide yes)
			(effects
				(font
					(size 1 1)
					(thickness 0.15)
				)
				(justify mirror)
			)
		)
		(property "License" "Apache-2.0"
			(at 309.91 -40.59 0)
			(layer "B.Fab")
			(hide yes)
			(effects
				(font
					(size 1 1)
					(thickness 0.15)
				)
				(justify mirror)
			)
		)
		(property "MPN" "C1005X6S1A105K050BC"
			(at 309.91 -40.59 0)
			(layer "B.Fab")
			(hide yes)
			(effects
				(font
					(size 1 1)
					(thickness 0.15)
				)
				(justify mirror)
			)
		)
		(property "Manufacturer" "TDK"
			(at 309.91 -40.59 0)
			(layer "B.Fab")
			(hide yes)
			(effects
				(font
					(size 1 1)
					(thickness 0.15)
				)
				(justify mirror)
			)
		)
		(property "Public" ""
			(at 309.91 -40.59 0)
			(layer "B.Fab")
			(hide yes)
			(effects
				(font
					(size 1 1)
					(thickness 0.15)
				)
				(justify mirror)
			)
		)
		(property "Val" "1u"
			(at 309.91 -40.59 0)
			(layer "B.Fab")
			(hide yes)
			(effects
				(font
					(size 1 1)
					(thickness 0.15)
				)
				(justify mirror)
			)
		)
		(property "Voltage" "16V"
			(at 309.91 -40.59 0)
			(layer "B.Fab")
			(hide yes)
			(effects
				(font
					(size 1 1)
					(thickness 0.15)
				)
				(justify mirror)
			)
		)
		(sheetname "/LPDDR4/")
		(sheetfile "lpddr.kicad_sch")
		(attr smd)
		(fp_rect
			(start -0.925 0.47)
			(end 0.925 -0.47)
			(stroke
				(width 0.05)
				(type default)
			)
			(fill no)
			(layer "B.CrtYd")
		)
		(fp_line
			(start 0.504 -0.248)
			(end -0.494 -0.248)
			(stroke
				(width 0.15)
				(type solid)
			)
			(layer "B.Fab")
		)
		(fp_line
			(start -0.494 -0.248)
			(end -0.494 0.25)
			(stroke
				(width 0.15)
				(type solid)
			)
			(layer "B.Fab")
		)
		(fp_line
			(start 0.504 0.25)
			(end 0.504 -0.248)
			(stroke
				(width 0.15)
				(type solid)
			)
			(layer "B.Fab")
		)
		(fp_line
			(start -0.494 0.25)
			(end 0.504 0.25)
			(stroke
				(width 0.15)
				(type solid)
			)
			(layer "B.Fab")
		)
		(fp_text user "License: Apache-2.0"
			(at -0.939 -5.799 270)
			(layer "B.Fab")
			(effects
				(font
					(size 0.7 0.7)
					(thickness 0.15)
				)
				(justify left bottom mirror)
			)
		)
		(fp_text user "${REFERENCE}"
			(at -0.939 -4.599 270)
			(layer "B.Fab")
			(effects
				(font
					(size 0.7 0.7)
					(thickness 0.15)
				)
				(justify left bottom mirror)
			)
		)
		(fp_text user "Author: Antmicro"
			(at -0.939 -3.399 270)
			(layer "B.Fab")
			(effects
				(font
					(size 0.7 0.7)
					(thickness 0.15)
				)
				(justify left bottom mirror)
			)
		)
		(pad "1" smd roundrect
			(at -0.48 0 90)
			(size 0.59 0.64)
			(layers "B.Cu" "B.Mask" "B.Paste")
			(roundrect_rratio 0.25)
			(net 417 "GND")
			(pintype "passive")
		)
		(pad "2" smd roundrect
			(at 0.48 0 90)
			(size 0.59 0.64)
			(layers "B.Cu" "B.Mask" "B.Paste")
			(roundrect_rratio 0.25)
			(net 48 "+1V8")
			(pintype "passive")
		)
	)
	(footprint "antmicro-footprints:C_0402_1005Metric"
		(layer "B.Cu")
		(at 182.4 122.45 180)
		(descr "Capacitor SMD 0402")
		(tags "capacitor SMD 0402")
		(property "Reference" "C162"
			(at -0.775 -1.425 0)
			(layer "B.SilkS")
			(effects
				(font
					(size 0.7 0.7)
					(thickness 0.15)
				)
				(justify left bottom mirror)
			)
		)
		(property "Value" "C_1u_0402"
			(at -1.022927 -2.155213 0)
			(layer "B.Fab")
			(hide yes)
			(effects
				(font
					(size 0.7 0.7)
					(thickness 0.15)
				)
				(justify left bottom mirror)
			)
		)
		(property "Datasheet" "https://product.tdk.com/en/search/capacitor/ceramic/mlcc/info?part_no=C1005X6S1A105K050BC"
			(at 0 0 180)
			(layer "F.Fab")
			(hide yes)
			(effects
				(font
					(size 1.27 1.27)
					(thickness 0.15)
				)
			)
		)
		(property "Description" "SMD Multilayer Ceramic Capacitor, 1 µF, 10 V, 0402 [1005 Metric], ± 10%, X6S, C"
			(at 0 0 180)
			(layer "F.Fab")
			(hide yes)
			(effects
				(font
					(size 1.27 1.27)
					(thickness 0.15)
				)
			)
		)
		(property "Author" "Antmicro"
			(at 364.8 244.9 0)
			(layer "B.Fab")
			(hide yes)
			(effects
				(font
					(size 1 1)
					(thickness 0.15)
				)
				(justify mirror)
			)
		)
		(property "Dielectric" "X5R"
			(at 364.8 244.9 0)
			(layer "B.Fab")
			(hide yes)
			(effects
				(font
					(size 1 1)
					(thickness 0.15)
				)
				(justify mirror)
			)
		)
		(property "License" "Apache-2.0"
			(at 364.8 244.9 0)
			(layer "B.Fab")
			(hide yes)
			(effects
				(font
					(size 1 1)
					(thickness 0.15)
				)
				(justify mirror)
			)
		)
		(property "MPN" "C1005X6S1A105K050BC"
			(at 364.8 244.9 0)
			(layer "B.Fab")
			(hide yes)
			(effects
				(font
					(size 1 1)
					(thickness 0.15)
				)
				(justify mirror)
			)
		)
		(property "Manufacturer" "TDK"
			(at 364.8 244.9 0)
			(layer "B.Fab")
			(hide yes)
			(effects
				(font
					(size 1 1)
					(thickness 0.15)
				)
				(justify mirror)
			)
		)
		(property "Public" ""
			(at 364.8 244.9 0)
			(layer "B.Fab")
			(hide yes)
			(effects
				(font
					(size 1 1)
					(thickness 0.15)
				)
				(justify mirror)
			)
		)
		(property "Val" "1u"
			(at 364.8 244.9 0)
			(layer "B.Fab")
			(hide yes)
			(effects
				(font
					(size 1 1)
					(thickness 0.15)
				)
				(justify mirror)
			)
		)
		(property "Voltage" "16V"
			(at 364.8 244.9 0)
			(layer "B.Fab")
			(hide yes)
			(effects
				(font
					(size 1 1)
					(thickness 0.15)
				)
				(justify mirror)
			)
		)
		(sheetname "/LPDDR4/")
		(sheetfile "lpddr.kicad_sch")
		(attr smd)
		(fp_rect
			(start -0.925 0.47)
			(end 0.925 -0.47)
			(stroke
				(width 0.05)
				(type default)
			)
			(fill no)
			(layer "B.CrtYd")
		)
		(fp_line
			(start 0.504 0.25)
			(end 0.504 -0.248)
			(stroke
				(width 0.15)
				(type solid)
			)
			(layer "B.Fab")
		)
		(fp_line
			(start 0.504 -0.248)
			(end -0.494 -0.248)
			(stroke
				(width 0.15)
				(type solid)
			)
			(layer "B.Fab")
		)
		(fp_line
			(start -0.494 0.25)
			(end 0.504 0.25)
			(stroke
				(width 0.15)
				(type solid)
			)
			(layer "B.Fab")
		)
		(fp_line
			(start -0.494 -0.248)
			(end -0.494 0.25)
			(stroke
				(width 0.15)
				(type solid)
			)
			(layer "B.Fab")
		)
		(fp_text user "License: Apache-2.0"
			(at -0.939 -5.799 0)
			(layer "B.Fab")
			(effects
				(font
					(size 0.7 0.7)
					(thickness 0.15)
				)
				(justify left bottom mirror)
			)
		)
		(fp_text user "Author: Antmicro"
			(at -0.939 -3.399 0)
			(layer "B.Fab")
			(effects
				(font
					(size 0.7 0.7)
					(thickness 0.15)
				)
				(justify left bottom mirror)
			)
		)
		(fp_text user "${REFERENCE}"
			(at -0.939 -4.599 0)
			(layer "B.Fab")
			(effects
				(font
					(size 0.7 0.7)
					(thickness 0.15)
				)
				(justify left bottom mirror)
			)
		)
		(pad "1" smd roundrect
			(at -0.48 0 180)
			(size 0.59 0.64)
			(layers "B.Cu" "B.Mask" "B.Paste")
			(roundrect_rratio 0.25)
			(net 417 "GND")
			(pintype "passive")
		)
		(pad "2" smd roundrect
			(at 0.48 0 180)
			(size 0.59 0.64)
			(layers "B.Cu" "B.Mask" "B.Paste")
			(roundrect_rratio 0.25)
			(net 2 "+1V1")
			(pintype "passive")
		)
	)
	(footprint "antmicro-footprints:R_0402_1005Metric"
		(layer "B.Cu")
		(at 186.8 120.85 -90)
		(descr "Resistor SMD 0402")
		(tags "resistor SMD 0402")
		(property "Reference" "R44"
			(at -4.875 -0.275 90)
			(layer "B.SilkS")
			(effects
				(font
					(size 0.7 0.7)
					(thickness 0.15)
				)
				(justify left bottom mirror)
			)
		)
		(property "Value" "R_1k_0402"
			(at -1.011843 -1.772047 90)
			(layer "B.Fab")
			(hide yes)
			(effects
				(font
					(size 0.7 0.7)
					(thickness 0.15)
				)
				(justify left bottom mirror)
			)
		)
		(property "Datasheet" "https://www.bourns.com/docs/product-datasheets/cr.pdf"
			(at 0 0 270)
			(layer "F.Fab")
			(hide yes)
			(effects
				(font
					(size 1.27 1.27)
					(thickness 0.15)
				)
			)
		)
		(property "Description" "SMD Chip Resistor, 1 kohm, ± 1%, 63 mW, 0402 [1005 Metric], Thick Film, General Purpose"
			(at 0 0 270)
			(layer "F.Fab")
			(hide yes)
			(effects
				(font
					(size 1.27 1.27)
					(thickness 0.15)
				)
			)
		)
		(property "Author" "Antmicro"
			(at 65.95 307.65 0)
			(layer "B.Fab")
			(hide yes)
			(effects
				(font
					(size 1 1)
					(thickness 0.15)
				)
				(justify mirror)
			)
		)
		(property "License" "Apache-2.0"
			(at 65.95 307.65 0)
			(layer "B.Fab")
			(hide yes)
			(effects
				(font
					(size 1 1)
					(thickness 0.15)
				)
				(justify mirror)
			)
		)
		(property "MPN" "CR0402-FX-1001GLF"
			(at 65.95 307.65 0)
			(layer "B.Fab")
			(hide yes)
			(effects
				(font
					(size 1 1)
					(thickness 0.15)
				)
				(justify mirror)
			)
		)
		(property "Manufacturer" "Bourns"
			(at 65.95 307.65 0)
			(layer "B.Fab")
			(hide yes)
			(effects
				(font
					(size 1 1)
					(thickness 0.15)
				)
				(justify mirror)
			)
		)
		(property "Public" ""
			(at 65.95 307.65 0)
			(layer "B.Fab")
			(hide yes)
			(effects
				(font
					(size 1 1)
					(thickness 0.15)
				)
				(justify mirror)
			)
		)
		(property "Tolerance" "1%"
			(at 65.95 307.65 0)
			(layer "B.Fab")
			(hide yes)
			(effects
				(font
					(size 1 1)
					(thickness 0.15)
				)
				(justify mirror)
			)
		)
		(property "Val" "1k"
			(at 65.95 307.65 0)
			(layer "B.Fab")
			(hide yes)
			(effects
				(font
					(size 1 1)
					(thickness 0.15)
				)
				(justify mirror)
			)
		)
		(sheetname "/FPGA Config/")
		(sheetfile "fpga-config.kicad_sch")
		(attr smd)
		(fp_rect
			(start -0.925 0.47)
			(end 0.925 -0.47)
			(stroke
				(width 0.05)
				(type default)
			)
			(fill no)
			(layer "B.CrtYd")
		)
		(fp_rect
			(start -0.5 0.25)
			(end 0.5 -0.25)
			(stroke
				(width 0.15)
				(type solid)
			)
			(fill no)
			(layer "B.Fab")
		)
		(fp_text user "Author: Antmicro"
			(at -0.95 -4.169 90)
			(layer "B.Fab")
			(effects
				(font
					(size 0.7 0.7)
					(thickness 0.15)
				)
				(justify left bottom mirror)
			)
		)
		(fp_text user "${REFERENCE}"
			(at -0.95 -3.168 90)
			(layer "B.Fab")
			(effects
				(font
					(size 0.7 0.7)
					(thickness 0.15)
				)
				(justify left bottom mirror)
			)
		)
		(fp_text user "License: Apache-2.0"
			(at -0.95 -5.169 90)
			(layer "B.Fab")
			(effects
				(font
					(size 0.7 0.7)
					(thickness 0.15)
				)
				(justify left bottom mirror)
			)
		)
		(pad "1" smd roundrect
			(at -0.48 0 270)
			(size 0.59 0.64)
			(layers "B.Cu" "B.Mask" "B.Paste")
			(roundrect_rratio 0.25)
			(net 127 "JTAG_RESET_n")
			(pintype "passive")
		)
		(pad "2" smd roundrect
			(at 0.48 0 270)
			(size 0.59 0.64)
			(layers "B.Cu" "B.Mask" "B.Paste")
			(roundrect_rratio 0.25)
			(net 50 "+3V3")
			(pintype "passive")
		)
	)
	(footprint "antmicro-footprints:C_0402_1005Metric"
		(layer "B.Cu")
		(at 177.2 130.9 90)
		(descr "Capacitor SMD 0402")
		(tags "capacitor SMD 0402")
		(property "Reference" "C144"
			(at 0.344 0.411 180)
			(layer "B.SilkS")
			(effects
				(font
					(size 0.7 0.7)
					(thickness 0.15)
				)
				(justify right bottom mirror)
			)
		)
		(property "Value" "C_1u_0402"
			(at -1.022927 -2.155213 90)
			(layer "B.Fab")
			(hide yes)
			(effects
				(font
					(size 0.7 0.7)
					(thickness 0.15)
				)
				(justify right bottom mirror)
			)
		)
		(property "Datasheet" "https://product.tdk.com/en/search/capacitor/ceramic/mlcc/info?part_no=C1005X6S1A105K050BC"
			(at 0 0 90)
			(layer "F.Fab")
			(hide yes)
			(effects
				(font
					(size 1.27 1.27)
					(thickness 0.15)
				)
			)
		)
		(property "Description" "SMD Multilayer Ceramic Capacitor, 1 µF, 10 V, 0402 [1005 Metric], ± 10%, X6S, C"
			(at 0 0 90)
			(layer "F.Fab")
			(hide yes)
			(effects
				(font
					(size 1.27 1.27)
					(thickness 0.15)
				)
			)
		)
		(property "Author" "Antmicro"
			(at 308.1 -46.3 0)
			(layer "B.Fab")
			(hide yes)
			(effects
				(font
					(size 1 1)
					(thickness 0.15)
				)
				(justify mirror)
			)
		)
		(property "Dielectric" "X5R"
			(at 308.1 -46.3 0)
			(layer "B.Fab")
			(hide yes)
			(effects
				(font
					(size 1 1)
					(thickness 0.15)
				)
				(justify mirror)
			)
		)
		(property "License" "Apache-2.0"
			(at 308.1 -46.3 0)
			(layer "B.Fab")
			(hide yes)
			(effects
				(font
					(size 1 1)
					(thickness 0.15)
				)
				(justify mirror)
			)
		)
		(property "MPN" "C1005X6S1A105K050BC"
			(at 308.1 -46.3 0)
			(layer "B.Fab")
			(hide yes)
			(effects
				(font
					(size 1 1)
					(thickness 0.15)
				)
				(justify mirror)
			)
		)
		(property "Manufacturer" "TDK"
			(at 308.1 -46.3 0)
			(layer "B.Fab")
			(hide yes)
			(effects
				(font
					(size 1 1)
					(thickness 0.15)
				)
				(justify mirror)
			)
		)
		(property "Public" ""
			(at 308.1 -46.3 0)
			(layer "B.Fab")
			(hide yes)
			(effects
				(font
					(size 1 1)
					(thickness 0.15)
				)
				(justify mirror)
			)
		)
		(property "Val" "1u"
			(at 308.1 -46.3 0)
			(layer "B.Fab")
			(hide yes)
			(effects
				(font
					(size 1 1)
					(thickness 0.15)
				)
				(justify mirror)
			)
		)
		(property "Voltage" "16V"
			(at 308.1 -46.3 0)
			(layer "B.Fab")
			(hide yes)
			(effects
				(font
					(size 1 1)
					(thickness 0.15)
				)
				(justify mirror)
			)
		)
		(sheetname "/LPDDR4/")
		(sheetfile "lpddr.kicad_sch")
		(attr smd)
		(fp_rect
			(start -0.925 0.47)
			(end 0.925 -0.47)
			(stroke
				(width 0.05)
				(type default)
			)
			(fill no)
			(layer "B.CrtYd")
		)
		(fp_line
			(start 0.504 -0.248)
			(end -0.494 -0.248)
			(stroke
				(width 0.15)
				(type solid)
			)
			(layer "B.Fab")
		)
		(fp_line
			(start -0.494 -0.248)
			(end -0.494 0.25)
			(stroke
				(width 0.15)
				(type solid)
			)
			(layer "B.Fab")
		)
		(fp_line
			(start 0.504 0.25)
			(end 0.504 -0.248)
			(stroke
				(width 0.15)
				(type solid)
			)
			(layer "B.Fab")
		)
		(fp_line
			(start -0.494 0.25)
			(end 0.504 0.25)
			(stroke
				(width 0.15)
				(type solid)
			)
			(layer "B.Fab")
		)
		(fp_text user "License: Apache-2.0"
			(at -0.939 -5.799 270)
			(layer "B.Fab")
			(effects
				(font
					(size 0.7 0.7)
					(thickness 0.15)
				)
				(justify left bottom mirror)
			)
		)
		(fp_text user "${REFERENCE}"
			(at -0.939 -4.599 270)
			(layer "B.Fab")
			(effects
				(font
					(size 0.7 0.7)
					(thickness 0.15)
				)
				(justify left bottom mirror)
			)
		)
		(fp_text user "Author: Antmicro"
			(at -0.939 -3.399 270)
			(layer "B.Fab")
			(effects
				(font
					(size 0.7 0.7)
					(thickness 0.15)
				)
				(justify left bottom mirror)
			)
		)
		(pad "1" smd roundrect
			(at -0.48 0 90)
			(size 0.59 0.64)
			(layers "B.Cu" "B.Mask" "B.Paste")
			(roundrect_rratio 0.25)
			(net 417 "GND")
			(pintype "passive")
		)
		(pad "2" smd roundrect
			(at 0.48 0 90)
			(size 0.59 0.64)
			(layers "B.Cu" "B.Mask" "B.Paste")
			(roundrect_rratio 0.25)
			(net 2 "+1V1")
			(pintype "passive")
		)
	)
)
